(kicad_pcb
	(version 20260206)
	(generator "pcbnew")
	(generator_version "10.0")
	(general
		(thickness 1.6)
		(legacy_teardrops no)
	)
	(paper "A4")
	(title_block
		(title "Bryce Canyon_F.DPB_16315-1-OCP.brd")
		(comment 1 "Bryce Canyon / footprints 1819-1825 of 2223")
	)
	(layers
		(0 "F.Cu" signal "TOP")
		(4 "In1.Cu" signal "L2GND")
		(6 "In2.Cu" signal "L3")
		(8 "In3.Cu" signal "L4GND")
		(10 "In4.Cu" signal "L5")
		(12 "In5.Cu" signal "L6VCC")
		(14 "In6.Cu" signal "L7VCC")
		(16 "In7.Cu" signal "L8")
		(18 "In8.Cu" signal "L9GND")
		(20 "In9.Cu" signal "L10")
		(22 "In10.Cu" signal "L11GND")
		(2 "B.Cu" signal "BOTTOM")
		(9 "F.Adhes" user "F.Adhesive")
		(11 "B.Adhes" user "B.Adhesive")
		(13 "F.Paste" user "Package Geometry/Pastemask Top")
		(15 "B.Paste" user "Package Geometry/Pastemask Bottom")
		(5 "F.SilkS" user "Ref Des/Silkscreen Top")
		(7 "B.SilkS" user "Ref Des/Silkscreen Bottom")
		(1 "F.Mask" user "Board Geometry/Soldermask Top")
		(3 "B.Mask" user "Board Geometry/Soldermask Bottom")
		(17 "Dwgs.User" user "User.Drawings")
		(19 "Cmts.User" user "User.Comments")
		(21 "Eco1.User" user "User.Eco1")
		(23 "Eco2.User" user "User.Eco2")
		(25 "Edge.Cuts" user "Board Geometry/Outline")
		(27 "Margin" user)
		(31 "F.CrtYd" user "Package Geometry/Place Bound Top")
		(29 "B.CrtYd" user "Package Geometry/Place Bound Bottom")
		(35 "F.Fab" user "Ref Des/Assembly Top")
		(33 "B.Fab" user "Ref Des/Assembly Bottom")
	)
	(footprint ""
		(layer "F.Cu")
		(at 430.438052 -157.585918 180)
		(property "Reference" "R624"
			(at 0 0 180)
			(layer "F.SilkS")
			(hide yes)
			(effects
				(font
					(size 1.27 1.27)
				)
			)
		)
		(property "Value" "0R2J-2-GP"
			(at 0.064008 -3.993896 180)
			(unlocked yes)
			(layer "F.Fab")
			(hide yes)
			(effects
				(font
					(size 1.016 1.016)
					(thickness 0.1524)
				)
			)
		)
		(property "Device Type" "R402H16"
			(at 0.064008 -5.517896 180)
			(unlocked yes)
			(layer "F.Fab")
			(hide yes)
			(effects
				(font
					(size 1.016 1.016)
					(thickness 0.1524)
				)
			)
		)
		(duplicate_pad_numbers_are_jumpers no)
		(fp_line
			(start 0.508 -0.9398)
			(end -0.508 -0.9398)
			(stroke
				(width 0.1524)
				(type default)
			)
			(layer "F.SilkS")
		)
		(fp_line
			(start -0.508 -0.9398)
			(end -0.508 0.9398)
			(stroke
				(width 0.1524)
				(type default)
			)
			(layer "F.SilkS")
		)
		(fp_rect
			(start -0.508 0.9398)
			(end 0.508 -0.9398)
			(stroke
				(width 0)
				(type default)
			)
			(fill no)
			(layer "F.CrtYd")
		)
		(fp_rect
			(start -0.508 0.9398)
			(end 0.508 -0.9398)
			(stroke
				(width 0)
				(type default)
			)
			(fill no)
			(layer "F.Fab")
		)
		(pad "1" smd custom
			(at 0 -0.4445 180)
			(size 0.1397 0.1397)
			(layers "F.Cu" "F.Mask" "F.Paste")
			(net "DRIVE_A_21_PWR")
			(options
				(clearance outline)
				(anchor circle)
			)
			(primitives
				(gr_poly
					(pts
						(arc
							(start -0.1778 -0.2794)
							(mid -0.249642 -0.249642)
							(end -0.2794 -0.1778)
						)
						(arc
							(start -0.2794 0.1778)
							(mid -0.249642 0.249642)
							(end -0.1778 0.2794)
						)
						(arc
							(start 0.1778 0.2794)
							(mid 0.249642 0.249642)
							(end 0.2794 0.1778)
						)
						(arc
							(start 0.2794 -0.1778)
							(mid 0.249642 -0.249642)
							(end 0.1778 -0.2794)
						)
					)
					(width 0)
					(fill yes)
				)
			)
		)
		(pad "2" smd custom
			(at 0 0.4445 180)
			(size 0.1397 0.1397)
			(layers "F.Cu" "F.Mask" "F.Paste")
			(net "SW_PWR_R_HDD21")
			(options
				(clearance outline)
				(anchor circle)
			)
			(primitives
				(gr_poly
					(pts
						(arc
							(start -0.1778 -0.2794)
							(mid -0.249642 -0.249642)
							(end -0.2794 -0.1778)
						)
						(arc
							(start -0.2794 0.1778)
							(mid -0.249642 0.249642)
							(end -0.1778 0.2794)
						)
						(arc
							(start 0.1778 0.2794)
							(mid 0.249642 0.249642)
							(end 0.2794 0.1778)
						)
						(arc
							(start 0.2794 -0.1778)
							(mid 0.249642 -0.249642)
							(end 0.1778 -0.2794)
						)
					)
					(width 0)
					(fill yes)
				)
			)
		)
	)
	(footprint ""
		(layer "F.Cu")
		(at 315.149992 -94.400116)
		(property "Reference" "FLED19"
			(at 0 0 0)
			(layer "F.SilkS")
			(hide yes)
			(effects
				(font
					(size 1.27 1.27)
				)
			)
		)
		(property "Value" "LED-BY-19-GP"
			(at -2.132076 1.414018 0)
			(unlocked yes)
			(layer "F.Fab")
			(hide yes)
			(effects
				(font
					(size 1.016 1.016)
					(thickness 0.1524)
				)
			)
		)
		(property "Device Type" "LED-1615-4PH26"
			(at -2.132076 -0.109982 0)
			(unlocked yes)
			(layer "F.Fab")
			(hide yes)
			(effects
				(font
					(size 1.016 1.016)
					(thickness 0.1524)
				)
			)
		)
		(duplicate_pad_numbers_are_jumpers no)
		(fp_line
			(start -1.2954 0.254)
			(end -1.2954 1.6002)
			(stroke
				(width 0.508)
				(type default)
			)
			(layer "F.SilkS")
		)
		(fp_line
			(start -1.2954 1.6002)
			(end 1.2954 1.6002)
			(stroke
				(width 0.508)
				(type default)
			)
			(layer "F.SilkS")
		)
		(fp_line
			(start -1.1176 -1.4224)
			(end 1.1176 -1.4224)
			(stroke
				(width 0.1524)
				(type default)
			)
			(layer "F.SilkS")
		)
		(fp_line
			(start -1.1176 1.4224)
			(end -1.1176 -1.4224)
			(stroke
				(width 0.1524)
				(type default)
			)
			(layer "F.SilkS")
		)
		(fp_line
			(start 1.1176 -1.4224)
			(end 1.1176 1.4224)
			(stroke
				(width 0.1524)
				(type default)
			)
			(layer "F.SilkS")
		)
		(fp_line
			(start 1.1176 1.4224)
			(end -1.1176 1.4224)
			(stroke
				(width 0.1524)
				(type default)
			)
			(layer "F.SilkS")
		)
		(fp_line
			(start 1.2954 1.6002)
			(end 1.2954 0.254)
			(stroke
				(width 0.508)
				(type default)
			)
			(layer "F.SilkS")
		)
		(fp_rect
			(start -0.7493 0.8001)
			(end 0.7493 -0.8001)
			(stroke
				(width 0)
				(type default)
			)
			(fill no)
			(layer "F.CrtYd")
		)
		(fp_poly
			(pts
				(xy -1.3716 1.6764) (xy -1.3716 -1.6764) (xy 1.3716 -1.6764) (xy 1.3716 0.0635) (xy 0.7493 0.0635)
				(xy 0.7493 -0.8001) (xy -0.7493 -0.8001) (xy -0.7493 0.8001) (xy 0.7493 0.8001) (xy 0.7493 0.0762)
				(xy 1.3716 0.0762) (xy 1.3716 1.6764)
			)
			(stroke
				(width 0)
				(type default)
			)
			(fill no)
			(layer "F.CrtYd")
		)
		(fp_rect
			(start -1.3716 1.6764)
			(end 1.3716 -1.6764)
			(stroke
				(width 0)
				(type default)
			)
			(fill no)
			(layer "F.Fab")
		)
		(pad "1" smd rect
			(at 0.50038 -0.73025)
			(size 0.7112 0.8636)
			(layers "F.Cu" "F.Mask" "F.Paste")
			(net "DRV_ACT_18")
		)
		(pad "2" smd rect
			(at -0.50038 -0.73025)
			(size 0.7112 0.8636)
			(layers "F.Cu" "F.Mask" "F.Paste")
			(net "FLT_HDD18")
		)
		(pad "3" smd rect
			(at 0.50038 0.73025)
			(size 0.7112 0.8636)
			(layers "F.Cu" "F.Mask" "F.Paste")
			(net "DRV_ACT_18_N")
		)
		(pad "4" smd rect
			(at -0.50038 0.73025)
			(size 0.7112 0.8636)
			(layers "F.Cu" "F.Mask" "F.Paste")
			(net "FLT_HDD018_N")
		)
	)
	(footprint ""
		(layer "F.Cu")
		(at 141.042898 -289.857942)
		(property "Reference" "Q26"
			(at 0 0 0)
			(layer "F.SilkS")
			(hide yes)
			(effects
				(font
					(size 1.27 1.27)
				)
			)
		)
		(property "Value" "AO4407AL-GP"
			(at -3.707384 -1.5367 0)
			(unlocked yes)
			(layer "F.Fab")
			(hide yes)
			(effects
				(font
					(size 1.016 1.016)
					(thickness 0.1524)
				)
			)
		)
		(property "Device Type" "SOIC8H69"
			(at -3.707384 -3.0607 0)
			(unlocked yes)
			(layer "F.Fab")
			(hide yes)
			(effects
				(font
					(size 1.016 1.016)
					(thickness 0.1524)
				)
			)
		)
		(duplicate_pad_numbers_are_jumpers no)
		(fp_line
			(start -2.7432 -1.4224)
			(end -2.7432 1.4224)
			(stroke
				(width 0.1524)
				(type default)
			)
			(layer "F.SilkS")
		)
		(fp_line
			(start -2.7432 1.4224)
			(end -2.6416 1.4224)
			(stroke
				(width 0.1524)
				(type default)
			)
			(layer "F.SilkS")
		)
		(fp_line
			(start -2.7432 1.4224)
			(end 2.1336 1.4224)
			(stroke
				(width 0.1524)
				(type default)
			)
			(layer "F.SilkS")
		)
		(fp_line
			(start -2.7178 -0.508)
			(end -2.1844 -0.0508)
			(stroke
				(width 0.1524)
				(type default)
			)
			(layer "F.SilkS")
		)
		(fp_line
			(start -2.6289 3.4417)
			(end -2.6289 1.4732)
			(stroke
				(width 0.381)
				(type default)
			)
			(layer "F.SilkS")
		)
		(fp_line
			(start -2.1844 -0.0508)
			(end -2.7178 0.508)
			(stroke
				(width 0.1524)
				(type default)
			)
			(layer "F.SilkS")
		)
		(fp_line
			(start 2.1336 -1.4224)
			(end -2.7432 -1.4224)
			(stroke
				(width 0.1524)
				(type default)
			)
			(layer "F.SilkS")
		)
		(fp_line
			(start 2.1336 1.4224)
			(end 2.1336 -1.4224)
			(stroke
				(width 0.1524)
				(type default)
			)
			(layer "F.SilkS")
		)
		(fp_poly
			(pts
				(xy -2.2098 -1.4224) (xy -2.2098 1.4224) (xy 2.2098 1.4224) (xy 2.2098 -1.4224)
			)
			(stroke
				(width 0)
				(type default)
			)
			(fill yes)
			(layer "F.SilkS")
		)
		(fp_rect
			(start -2.450084 2.999994)
			(end 2.450084 -2.999994)
			(stroke
				(width 0)
				(type default)
			)
			(fill no)
			(layer "F.CrtYd")
		)
		(fp_poly
			(pts
				(xy -2.8194 3.6322) (xy -2.8194 -3.6322) (xy 2.8194 -3.6322) (xy 2.8194 1.18364) (xy 2.450084 1.18364)
				(xy 2.450084 -2.999994) (xy -2.450084 -2.999994) (xy -2.450084 2.999994) (xy 2.450084 2.999994)
				(xy 2.450084 1.18618) (xy 2.8194 1.18618) (xy 2.8194 3.6322)
			)
			(stroke
				(width 0)
				(type default)
			)
			(fill no)
			(layer "F.CrtYd")
		)
		(fp_rect
			(start -2.8194 3.6322)
			(end 2.8194 -3.6322)
			(stroke
				(width 0)
				(type default)
			)
			(fill no)
			(layer "F.Fab")
		)
		(pad "1" smd rect
			(at -1.905 2.54)
			(size 0.635 1.651)
			(layers "F.Cu" "F.Mask" "F.Paste")
			(net "P12V_A")
		)
		(pad "2" smd rect
			(at -0.635 2.54)
			(size 0.635 1.651)
			(layers "F.Cu" "F.Mask" "F.Paste")
			(net "P12V_A")
		)
		(pad "3" smd rect
			(at 0.635 2.54)
			(size 0.635 1.651)
			(layers "F.Cu" "F.Mask" "F.Paste")
			(net "P12V_A")
		)
		(pad "4" smd rect
			(at 1.905 2.54)
			(size 0.635 1.651)
			(layers "F.Cu" "F.Mask" "F.Paste")
			(net "SW_HDD_N4")
		)
		(pad "5" smd rect
			(at 1.905 -2.54)
			(size 0.635 1.651)
			(layers "F.Cu" "F.Mask" "F.Paste")
			(net "P12V_HDD4")
		)
		(pad "6" smd rect
			(at 0.635 -2.54)
			(size 0.635 1.651)
			(layers "F.Cu" "F.Mask" "F.Paste")
			(net "P12V_HDD4")
		)
		(pad "7" smd rect
			(at -0.635 -2.54)
			(size 0.635 1.651)
			(layers "F.Cu" "F.Mask" "F.Paste")
			(net "P12V_HDD4")
		)
		(pad "8" smd rect
			(at -1.905 -2.54)
			(size 0.635 1.651)
			(layers "F.Cu" "F.Mask" "F.Paste")
			(net "P12V_HDD4")
		)
	)
	(footprint ""
		(layer "F.Cu")
		(at 111.795052 -242.25377)
		(property "Reference" "R219"
			(at 0 0 0)
			(layer "F.SilkS")
			(hide yes)
			(effects
				(font
					(size 1.27 1.27)
				)
			)
		)
		(property "Value" "130R3F-GP"
			(at -0.0254 -2.5146 0)
			(unlocked yes)
			(layer "F.Fab")
			(hide yes)
			(effects
				(font
					(size 1.016 1.016)
					(thickness 0.1524)
				)
			)
		)
		(property "Device Type" "R603H22"
			(at -0.0254 -4.0386 0)
			(unlocked yes)
			(layer "F.Fab")
			(hide yes)
			(effects
				(font
					(size 1.016 1.016)
					(thickness 0.1524)
				)
			)
		)
		(duplicate_pad_numbers_are_jumpers no)
		(fp_line
			(start -0.4826 0)
			(end -0.2032 0)
			(stroke
				(width 0.2032)
				(type default)
			)
			(layer "F.SilkS")
		)
		(fp_line
			(start 0.2032 0)
			(end 0.4826 0)
			(stroke
				(width 0.2032)
				(type default)
			)
			(layer "F.SilkS")
		)
		(fp_rect
			(start -0.5842 1.3335)
			(end 0.5842 -1.3335)
			(stroke
				(width 0)
				(type default)
			)
			(fill no)
			(layer "F.CrtYd")
		)
		(fp_rect
			(start -0.5842 1.3335)
			(end 0.5842 -1.3335)
			(stroke
				(width 0)
				(type default)
			)
			(fill no)
			(layer "F.Fab")
		)
		(pad "1" smd custom
			(at 0 -0.762)
			(size 0.2159 0.2159)
			(layers "F.Cu" "F.Mask" "F.Paste")
			(net "P5V_A_1")
			(options
				(clearance outline)
				(anchor circle)
			)
			(primitives
				(gr_poly
					(pts
						(arc
							(start -0.3302 -0.4318)
							(mid -0.402042 -0.402042)
							(end -0.4318 -0.3302)
						)
						(arc
							(start -0.4318 0.3302)
							(mid -0.402042 0.402042)
							(end -0.3302 0.4318)
						)
						(arc
							(start 0.3302 0.4318)
							(mid 0.402042 0.402042)
							(end 0.4318 0.3302)
						)
						(arc
							(start 0.4318 -0.3302)
							(mid 0.402042 -0.402042)
							(end 0.3302 -0.4318)
						)
					)
					(width 0)
					(fill yes)
				)
			)
		)
		(pad "2" smd custom
			(at 0 0.762)
			(size 0.2159 0.2159)
			(layers "F.Cu" "F.Mask" "F.Paste")
			(net "FLT_HDD3")
			(options
				(clearance outline)
				(anchor circle)
			)
			(primitives
				(gr_poly
					(pts
						(arc
							(start -0.3302 -0.4318)
							(mid -0.402042 -0.402042)
							(end -0.4318 -0.3302)
						)
						(arc
							(start -0.4318 0.3302)
							(mid -0.402042 0.402042)
							(end -0.3302 0.4318)
						)
						(arc
							(start 0.3302 0.4318)
							(mid 0.402042 0.402042)
							(end 0.4318 0.3302)
						)
						(arc
							(start 0.4318 -0.3302)
							(mid 0.402042 -0.402042)
							(end 0.3302 -0.4318)
						)
					)
					(width 0)
					(fill yes)
				)
			)
		)
	)
	(footprint ""
		(layer "F.Cu")
		(at 237.470696 -262.22706 90)
		(property "Reference" "R424"
			(at 0 0 90)
			(layer "F.SilkS")
			(hide yes)
			(effects
				(font
					(size 1.27 1.27)
				)
			)
		)
		(property "Value" "10KR2F-2-GP"
			(at 0.064008 -3.993896 90)
			(unlocked yes)
			(layer "F.Fab")
			(hide yes)
			(effects
				(font
					(size 1.016 1.016)
					(thickness 0.1524)
				)
			)
		)
		(property "Device Type" "R402H16"
			(at 0.064008 -5.517896 90)
			(unlocked yes)
			(layer "F.Fab")
			(hide yes)
			(effects
				(font
					(size 1.016 1.016)
					(thickness 0.1524)
				)
			)
		)
		(duplicate_pad_numbers_are_jumpers no)
		(fp_line
			(start 0.508 -0.9398)
			(end -0.508 -0.9398)
			(stroke
				(width 0.1524)
				(type default)
			)
			(layer "F.SilkS")
		)
		(fp_line
			(start -0.508 -0.9398)
			(end -0.508 0.9398)
			(stroke
				(width 0.1524)
				(type default)
			)
			(layer "F.SilkS")
		)
		(fp_rect
			(start -0.508 0.9398)
			(end 0.508 -0.9398)
			(stroke
				(width 0)
				(type default)
			)
			(fill no)
			(layer "F.CrtYd")
		)
		(fp_rect
			(start -0.508 0.9398)
			(end 0.508 -0.9398)
			(stroke
				(width 0)
				(type default)
			)
			(fill no)
			(layer "F.Fab")
		)
		(pad "1" smd custom
			(at 0 -0.4445 90)
			(size 0.1397 0.1397)
			(layers "F.Cu" "F.Mask" "F.Paste")
			(net "P3V3_STBY_A")
			(options
				(clearance outline)
				(anchor circle)
			)
			(primitives
				(gr_poly
					(pts
						(arc
							(start -0.1778 -0.2794)
							(mid -0.249642 -0.249642)
							(end -0.2794 -0.1778)
						)
						(arc
							(start -0.2794 0.1778)
							(mid -0.249642 0.249642)
							(end -0.1778 0.2794)
						)
						(arc
							(start 0.1778 0.2794)
							(mid 0.249642 0.249642)
							(end 0.2794 0.1778)
						)
						(arc
							(start 0.2794 -0.1778)
							(mid 0.249642 -0.249642)
							(end 0.1778 -0.2794)
						)
					)
					(width 0)
					(fill yes)
				)
			)
		)
		(pad "2" smd custom
			(at 0 0.4445 90)
			(size 0.1397 0.1397)
			(layers "F.Cu" "F.Mask" "F.Paste")
			(net "DRIVE_INSERT_ALERT_A_N")
			(options
				(clearance outline)
				(anchor circle)
			)
			(primitives
				(gr_poly
					(pts
						(arc
							(start -0.1778 -0.2794)
							(mid -0.249642 -0.249642)
							(end -0.2794 -0.1778)
						)
						(arc
							(start -0.2794 0.1778)
							(mid -0.249642 0.249642)
							(end -0.1778 0.2794)
						)
						(arc
							(start 0.1778 0.2794)
							(mid 0.249642 0.249642)
							(end 0.2794 0.1778)
						)
						(arc
							(start 0.2794 -0.1778)
							(mid 0.249642 -0.249642)
							(end 0.1778 -0.2794)
						)
					)
					(width 0)
					(fill yes)
				)
			)
		)
	)
	(footprint ""
		(layer "F.Cu")
		(at 464.2739 -49.443894 90)
		(property "Reference" "R928"
			(at 0 0 90)
			(layer "F.SilkS")
			(hide yes)
			(effects
				(font
					(size 1.27 1.27)
				)
			)
		)
		(property "Value" "200KR2F-L-GP"
			(at 0.064008 -3.993896 90)
			(unlocked yes)
			(layer "F.Fab")
			(hide yes)
			(effects
				(font
					(size 1.016 1.016)
					(thickness 0.1524)
				)
			)
		)
		(property "Device Type" "R402H16"
			(at 0.064008 -5.517896 90)
			(unlocked yes)
			(layer "F.Fab")
			(hide yes)
			(effects
				(font
					(size 1.016 1.016)
					(thickness 0.1524)
				)
			)
		)
		(duplicate_pad_numbers_are_jumpers no)
		(fp_line
			(start 0.508 -0.9398)
			(end -0.508 -0.9398)
			(stroke
				(width 0.1524)
				(type default)
			)
			(layer "F.SilkS")
		)
		(fp_line
			(start -0.508 -0.9398)
			(end -0.508 0.9398)
			(stroke
				(width 0.1524)
				(type default)
			)
			(layer "F.SilkS")
		)
		(fp_rect
			(start -0.508 0.9398)
			(end 0.508 -0.9398)
			(stroke
				(width 0)
				(type default)
			)
			(fill no)
			(layer "F.CrtYd")
		)
		(fp_rect
			(start -0.508 0.9398)
			(end 0.508 -0.9398)
			(stroke
				(width 0)
				(type default)
			)
			(fill no)
			(layer "F.Fab")
		)
		(pad "1" smd custom
			(at 0 -0.4445 90)
			(size 0.1397 0.1397)
			(layers "F.Cu" "F.Mask" "F.Paste")
			(net "SW_HDD_R34")
			(options
				(clearance outline)
				(anchor circle)
			)
			(primitives
				(gr_poly
					(pts
						(arc
							(start -0.1778 -0.2794)
							(mid -0.249642 -0.249642)
							(end -0.2794 -0.1778)
						)
						(arc
							(start -0.2794 0.1778)
							(mid -0.249642 0.249642)
							(end -0.1778 0.2794)
						)
						(arc
							(start 0.1778 0.2794)
							(mid 0.249642 0.249642)
							(end 0.2794 0.1778)
						)
						(arc
							(start 0.2794 -0.1778)
							(mid 0.249642 -0.249642)
							(end 0.1778 -0.2794)
						)
					)
					(width 0)
					(fill yes)
				)
			)
		)
		(pad "2" smd custom
			(at 0 0.4445 90)
			(size 0.1397 0.1397)
			(layers "F.Cu" "F.Mask" "F.Paste")
			(net "SW_HDD_N34")
			(options
				(clearance outline)
				(anchor circle)
			)
			(primitives
				(gr_poly
					(pts
						(arc
							(start -0.1778 -0.2794)
							(mid -0.249642 -0.249642)
							(end -0.2794 -0.1778)
						)
						(arc
							(start -0.2794 0.1778)
							(mid -0.249642 0.249642)
							(end -0.1778 0.2794)
						)
						(arc
							(start 0.1778 0.2794)
							(mid 0.249642 0.249642)
							(end 0.2794 0.1778)
						)
						(arc
							(start 0.2794 -0.1778)
							(mid 0.249642 -0.249642)
							(end 0.1778 -0.2794)
						)
					)
					(width 0)
					(fill yes)
				)
			)
		)
	)
	(footprint ""
		(layer "F.Cu")
		(at 476.8596 -67.3608)
		(property "Reference" "TP177"
			(at 0 0 0)
			(layer "F.SilkS")
			(hide yes)
			(effects
				(font
					(size 1.27 1.27)
				)
			)
		)
		(property "Value" "TPAD32-GP"
			(at -0.0508 -1.6764 0)
			(unlocked yes)
			(layer "F.Fab")
			(hide yes)
			(effects
				(font
					(size 1.016 1.016)
					(thickness 0.1524)
				)
			)
		)
		(property "Device Type" "TPAD32"
			(at -0.0508 -3.2004 0)
			(unlocked yes)
			(layer "F.Fab")
			(hide yes)
			(effects
				(font
					(size 1.016 1.016)
					(thickness 0.1524)
				)
			)
		)
		(duplicate_pad_numbers_are_jumpers no)
		(fp_poly
			(pts
				(arc
					(start 0.4064 0)
					(mid -0.4064 0)
					(end 0.4064 0)
				)
			)
			(stroke
				(width 0)
				(type default)
			)
			(fill no)
			(layer "F.CrtYd")
		)
		(fp_poly
			(pts
				(arc
					(start 0.7112 0)
					(mid -0.7112 0)
					(end 0.7112 0)
				)
			)
			(stroke
				(width 0)
				(type default)
			)
			(fill no)
			(layer "F.Fab")
		)
		(pad "1" smd circle
			(at 0 0)
			(size 0.8128 0.8128)
			(layers "F.Cu" "F.Mask" "F.Paste")
			(net "ACT_HDD_35")
		)
	)
)
